# TIMECARD (Time Appliance Project (Time Card)) — schematic netlist excerpt (pin names and nets, part order shuffled) for the footprints in the layout excerpt that follows; sources: Cadence DE-HDL packaged netlist, KiCad conversion of R4006-B0001-02_R01.brd

C71  CAPACITOR  0.1UF 25V 10%  pkg SMC_0402R_H022  page 21 : \1\ = XP5R0V_MAC_USB ; \2\ = SG
C57  CAPACITOR  1000PF 50V 5%  pkg SMC_0402R_H022  page 28 : \1\ = XP3R3V_SW ; \2\ = UNNAMED_517_CAPACITOR_I29_2

(kicad_pcb
	(version 20260206)
	(generator "pcbnew")
	(generator_version "10.0")
	(general
		(thickness 1.6)
		(legacy_teardrops no)
	)
	(paper "A4")
	(title_block
		(title "timecard-production-celestica-r4006 — R4006-B0001-02_R01.brd")
		(comment 1 "Time Appliance Project (Time Card) / footprints 907-908 of 1113")
	)
	(layers
		(0 "F.Cu" signal "TOP")
		(4 "In1.Cu" signal "L02_GND1")
		(6 "In2.Cu" signal "L03_SIG1")
		(8 "In3.Cu" signal "L04_GND2")
		(10 "In4.Cu" signal "L05_VCC1")
		(12 "In5.Cu" signal "L06_VCC2")
		(14 "In6.Cu" signal "L07_GND3")
		(16 "In7.Cu" signal "L08_SIG2")
		(18 "In8.Cu" signal "L09_GND4")
		(2 "B.Cu" signal "BOTTOM")
		(9 "F.Adhes" user "F.Adhesive")
		(11 "B.Adhes" user "B.Adhesive")
		(13 "F.Paste" user "Package Geometry/Pastemask Top")
		(15 "B.Paste" user "Package Geometry/Pastemask Bottom")
		(5 "F.SilkS" user "Ref Des/Silkscreen Top")
		(7 "B.SilkS" user "Ref Des/Silkscreen Bottom")
		(1 "F.Mask" user "Board Geometry/Soldermask Top")
		(3 "B.Mask" user "Board Geometry/Soldermask Bottom")
		(17 "Dwgs.User" user "User.Drawings")
		(19 "Cmts.User" user "User.Comments")
		(21 "Eco1.User" user "User.Eco1")
		(23 "Eco2.User" user "User.Eco2")
		(25 "Edge.Cuts" user "Board Geometry/Outline")
		(27 "Margin" user)
		(31 "F.CrtYd" user "Package Geometry/Place Bound Top")
		(29 "B.CrtYd" user "Package Geometry/Place Bound Bottom")
		(35 "F.Fab" user "Ref Des/Assembly Top")
		(33 "B.Fab" user "Ref Des/Assembly Bottom")
	)
	(footprint ""
		(layer "B.Cu")
		(at 80.899 -99.06 90)
		(property "Reference" "C57"
			(at 0.127 -1.43637 270)
			(unlocked yes)
			(layer "B.SilkS")
			(effects
				(font
					(size 0.7874 0.5842)
					(thickness 0.1524)
				)
				(justify mirror)
			)
		)
		(property "Value" "VAL*"
			(at -0.0762 2.067306 90)
			(unlocked yes)
			(layer "B.Fab")
			(hide yes)
			(effects
				(font
					(size 0.7874 0.5842)
					(thickness 0.1524)
				)
				(justify mirror)
			)
		)
		(property "Tolerance" "TOL*"
			(at -0.0762 3.032506 90)
			(unlocked yes)
			(layer "Cmts.User")
			(hide yes)
			(effects
				(font
					(size 0.7874 0.5842)
					(thickness 0.1524)
				)
				(justify mirror)
			)
		)
		(property "User Part Number" "PARTNUM*"
			(at -0.1016 4.023106 90)
			(unlocked yes)
			(layer "Cmts.User")
			(hide yes)
			(effects
				(font
					(size 0.7874 0.5842)
					(thickness 0.1524)
				)
				(justify mirror)
			)
		)
		(property "Device Type" "CAPACITOR-G105-0A102-FJ,1000PFA"
			(at -0.0508 1.127506 90)
			(unlocked yes)
			(layer "B.Fab")
			(hide yes)
			(effects
				(font
					(size 0.7874 0.5842)
					(thickness 0.1524)
				)
				(justify mirror)
			)
		)
		(duplicate_pad_numbers_are_jumpers no)
		(fp_line
			(start 1.143 -0.5588)
			(end 1.143 0.5588)
			(stroke
				(width 0.1)
				(type default)
			)
			(layer "B.SilkS")
		)
		(fp_line
			(start -1.143 -0.5588)
			(end 1.143 -0.5588)
			(stroke
				(width 0.1)
				(type default)
			)
			(layer "B.SilkS")
		)
		(fp_line
			(start 1.143 0.5588)
			(end -1.143 0.5588)
			(stroke
				(width 0.1)
				(type default)
			)
			(layer "B.SilkS")
		)
		(fp_line
			(start -1.143 0.5588)
			(end -1.143 -0.5588)
			(stroke
				(width 0.1)
				(type default)
			)
			(layer "B.SilkS")
		)
		(fp_rect
			(start -1.143 -0.5588)
			(end 1.143 0.5588)
			(stroke
				(width 0)
				(type default)
			)
			(fill no)
			(layer "B.CrtYd")
		)
		(fp_line
			(start 0.508 -0.3048)
			(end 0.508 0.3048)
			(stroke
				(width 0.1)
				(type default)
			)
			(layer "B.Fab")
		)
		(fp_line
			(start -0.508 -0.3048)
			(end 0.508 -0.3048)
			(stroke
				(width 0.1)
				(type default)
			)
			(layer "B.Fab")
		)
		(fp_line
			(start 0.508 0.3048)
			(end -0.508 0.3048)
			(stroke
				(width 0.1)
				(type default)
			)
			(layer "B.Fab")
		)
		(fp_line
			(start -0.508 0.3048)
			(end -0.508 -0.3048)
			(stroke
				(width 0.1)
				(type default)
			)
			(layer "B.Fab")
		)
		(pad "1" smd rect
			(at 0.5334 0 270)
			(size 0.7112 0.6096)
			(layers "B.Cu" "B.Mask" "B.Paste")
			(net "XP3R3V_SW")
		)
		(pad "2" smd rect
			(at -0.5334 0 270)
			(size 0.7112 0.6096)
			(layers "B.Cu" "B.Mask" "B.Paste")
			(net "UNNAMED_517_CAPACITOR_I29_2")
		)
		(zone
			(layer "B.Cu")
			(hatch none 0.5)
			(connect_pads
				(clearance 0)
			)
			(min_thickness 0.25)
			(keepout
				(tracks allowed)
				(vias not_allowed)
				(pads allowed)
				(copperpour not_allowed)
				(footprints allowed)
			)
			(placement
				(enabled no)
				(sheetname "")
			)
			(fill
				(thermal_gap 0.5)
				(thermal_bridge_width 0.5)
				(island_removal_mode 0)
			)
			(polygon
				(pts
					(xy 80.5942 -98.9838) (xy 81.2038 -98.9838) (xy 81.2038 -99.1362) (xy 80.5942 -99.1362)
				)
			)
		)
	)
	(footprint ""
		(layer "B.Cu")
		(at 70.866 -55.499 -90)
		(property "Reference" "C71"
			(at 2.159 -0.21463 270)
			(unlocked yes)
			(layer "B.SilkS")
			(effects
				(font
					(size 0.7874 0.5842)
					(thickness 0.1524)
				)
				(justify mirror)
			)
		)
		(property "Value" "VAL*"
			(at -0.0762 2.067306 270)
			(unlocked yes)
			(layer "B.Fab")
			(hide yes)
			(effects
				(font
					(size 0.7874 0.5842)
					(thickness 0.1524)
				)
				(justify mirror)
			)
		)
		(property "Device Type" "CAPACITOR-G105-0B104-EK,0.1UF,A"
			(at -0.0508 1.127506 270)
			(unlocked yes)
			(layer "B.Fab")
			(hide yes)
			(effects
				(font
					(size 0.7874 0.5842)
					(thickness 0.1524)
				)
				(justify mirror)
			)
		)
		(property "User Part Number" "PARTNUM*"
			(at -0.1016 4.023106 270)
			(unlocked yes)
			(layer "Cmts.User")
			(hide yes)
			(effects
				(font
					(size 0.7874 0.5842)
					(thickness 0.1524)
				)
				(justify mirror)
			)
		)
		(property "Tolerance" "TOL*"
			(at -0.0762 3.032506 270)
			(unlocked yes)
			(layer "Cmts.User")
			(hide yes)
			(effects
				(font
					(size 0.7874 0.5842)
					(thickness 0.1524)
				)
				(justify mirror)
			)
		)
		(duplicate_pad_numbers_are_jumpers no)
		(fp_line
			(start -1.143 0.5588)
			(end -1.143 -0.5588)
			(stroke
				(width 0.1)
				(type default)
			)
			(layer "B.SilkS")
		)
		(fp_line
			(start 1.143 0.5588)
			(end -1.143 0.5588)
			(stroke
				(width 0.1)
				(type default)
			)
			(layer "B.SilkS")
		)
		(fp_line
			(start -1.143 -0.5588)
			(end 1.143 -0.5588)
			(stroke
				(width 0.1)
				(type default)
			)
			(layer "B.SilkS")
		)
		(fp_line
			(start 1.143 -0.5588)
			(end 1.143 0.5588)
			(stroke
				(width 0.1)
				(type default)
			)
			(layer "B.SilkS")
		)
		(fp_rect
			(start 1.143 0.5588)
			(end -1.143 -0.5588)
			(stroke
				(width 0)
				(type default)
			)
			(fill no)
			(layer "B.CrtYd")
		)
		(fp_line
			(start -0.508 0.3048)
			(end -0.508 -0.3048)
			(stroke
				(width 0.1)
				(type default)
			)
			(layer "B.Fab")
		)
		(fp_line
			(start 0.508 0.3048)
			(end -0.508 0.3048)
			(stroke
				(width 0.1)
				(type default)
			)
			(layer "B.Fab")
		)
		(fp_line
			(start -0.508 -0.3048)
			(end 0.508 -0.3048)
			(stroke
				(width 0.1)
				(type default)
			)
			(layer "B.Fab")
		)
		(fp_line
			(start 0.508 -0.3048)
			(end 0.508 0.3048)
			(stroke
				(width 0.1)
				(type default)
			)
			(layer "B.Fab")
		)
		(pad "1" smd rect
			(at 0.5334 0 90)
			(size 0.7112 0.6096)
			(layers "B.Cu" "B.Mask" "B.Paste")
			(net "XP5R0V_MAC_USB")
		)
		(pad "2" smd rect
			(at -0.5334 0 90)
			(size 0.7112 0.6096)
			(layers "B.Cu" "B.Mask" "B.Paste")
			(net "SG")
		)
		(zone
			(layer "B.Cu")
			(hatch none 0.5)
			(connect_pads
				(clearance 0)
			)
			(min_thickness 0.25)
			(keepout
				(tracks allowed)
				(vias not_allowed)
				(pads allowed)
				(copperpour not_allowed)
				(footprints allowed)
			)
			(placement
				(enabled no)
				(sheetname "")
			)
			(fill
				(thermal_gap 0.5)
				(thermal_bridge_width 0.5)
				(island_removal_mode 0)
			)
			(polygon
				(pts
					(xy 70.5612 -55.4228) (xy 71.1708 -55.4228) (xy 71.1708 -55.5752) (xy 70.5612 -55.5752)
				)
			)
		)
	)
)
